(kicad_pcb
	(version 20260206)
	(generator "pcbnew")
	(generator_version "10.0")
	(general
		(thickness 1.6)
		(legacy_teardrops no)
	)
	(paper "A4")
	(title_block
		(title "peb — Lightning_PEB_BRD.brd")
		(comment 1 "Lightning (Wiwynn / Facebook NVMe JBOF) / footprints 1278-1283 of 2563")
	)
	(layers
		(0 "F.Cu" signal "TOP")
		(4 "In1.Cu" signal "L2GND")
		(6 "In2.Cu" signal "L3")
		(8 "In3.Cu" signal "L4VCC")
		(10 "In4.Cu" signal "L5VCC")
		(12 "In5.Cu" signal "L6")
		(14 "In6.Cu" signal "L7GND")
		(2 "B.Cu" signal "BOTTOM")
		(9 "F.Adhes" user "F.Adhesive")
		(11 "B.Adhes" user "B.Adhesive")
		(13 "F.Paste" user "Package Geometry/Pastemask Top")
		(15 "B.Paste" user "Package Geometry/Pastemask Bottom")
		(5 "F.SilkS" user "Ref Des/Silkscreen Top")
		(7 "B.SilkS" user "Ref Des/Silkscreen Bottom")
		(1 "F.Mask" user "Board Geometry/Soldermask Top")
		(3 "B.Mask" user "Board Geometry/Soldermask Bottom")
		(17 "Dwgs.User" user "User.Drawings")
		(19 "Cmts.User" user "User.Comments")
		(21 "Eco1.User" user "User.Eco1")
		(23 "Eco2.User" user "User.Eco2")
		(25 "Edge.Cuts" user "Board Geometry/Outline")
		(27 "Margin" user)
		(31 "F.CrtYd" user "Package Geometry/Place Bound Top")
		(29 "B.CrtYd" user "Package Geometry/Place Bound Bottom")
		(35 "F.Fab" user "Ref Des/Assembly Top")
		(33 "B.Fab" user "Ref Des/Assembly Bottom")
	)
	(footprint ""
		(layer "F.Cu")
		(at 54.229 -114.7572)
		(property "Reference" "R642"
			(at 0 0 0)
			(layer "F.SilkS")
			(hide yes)
			(effects
				(font
					(size 1.27 1.27)
				)
			)
		)
		(property "Value" "0R2J-2-GP"
			(at 0.064008 -3.993896 0)
			(unlocked yes)
			(layer "F.Fab")
			(hide yes)
			(effects
				(font
					(size 1.016 1.016)
					(thickness 0.1524)
				)
			)
		)
		(property "Device Type" "R402H16"
			(at 0.064008 -5.517896 0)
			(unlocked yes)
			(layer "F.Fab")
			(hide yes)
			(effects
				(font
					(size 1.016 1.016)
					(thickness 0.1524)
				)
			)
		)
		(duplicate_pad_numbers_are_jumpers no)
		(fp_line
			(start -0.508 -0.9398)
			(end -0.508 0.9398)
			(stroke
				(width 0.1524)
				(type default)
			)
			(layer "F.SilkS")
		)
		(fp_line
			(start 0.508 -0.9398)
			(end -0.508 -0.9398)
			(stroke
				(width 0.1524)
				(type default)
			)
			(layer "F.SilkS")
		)
		(fp_rect
			(start -0.508 0.9398)
			(end 0.508 -0.9398)
			(stroke
				(width 0)
				(type default)
			)
			(fill no)
			(layer "F.CrtYd")
		)
		(fp_rect
			(start -0.508 0.9398)
			(end 0.508 -0.9398)
			(stroke
				(width 0)
				(type default)
			)
			(fill no)
			(layer "F.Fab")
		)
		(pad "1" smd custom
			(at 0 -0.4445)
			(size 0.1397 0.1397)
			(layers "F.Cu" "F.Mask" "F.Paste")
			(net "BMC0_SCL13_R")
			(options
				(clearance outline)
				(anchor circle)
			)
			(primitives
				(gr_poly
					(pts
						(arc
							(start -0.1778 -0.2794)
							(mid -0.249642 -0.249642)
							(end -0.2794 -0.1778)
						)
						(arc
							(start -0.2794 0.1778)
							(mid -0.249642 0.249642)
							(end -0.1778 0.2794)
						)
						(arc
							(start 0.1778 0.2794)
							(mid 0.249642 0.249642)
							(end 0.2794 0.1778)
						)
						(arc
							(start 0.2794 -0.1778)
							(mid 0.249642 -0.249642)
							(end 0.1778 -0.2794)
						)
					)
					(width 0)
					(fill yes)
				)
			)
		)
		(pad "2" smd custom
			(at 0 0.4445)
			(size 0.1397 0.1397)
			(layers "F.Cu" "F.Mask" "F.Paste")
			(net "BMC_I2C13_MINI7_SCL_S")
			(options
				(clearance outline)
				(anchor circle)
			)
			(primitives
				(gr_poly
					(pts
						(arc
							(start -0.1778 -0.2794)
							(mid -0.249642 -0.249642)
							(end -0.2794 -0.1778)
						)
						(arc
							(start -0.2794 0.1778)
							(mid -0.249642 0.249642)
							(end -0.1778 0.2794)
						)
						(arc
							(start 0.1778 0.2794)
							(mid 0.249642 0.249642)
							(end 0.2794 0.1778)
						)
						(arc
							(start 0.2794 -0.1778)
							(mid 0.249642 -0.249642)
							(end 0.1778 -0.2794)
						)
					)
					(width 0)
					(fill yes)
				)
			)
		)
	)
	(footprint ""
		(layer "F.Cu")
		(at 80.0862 -86.106)
		(property "Reference" "R484"
			(at 0 0 0)
			(layer "F.SilkS")
			(hide yes)
			(effects
				(font
					(size 1.27 1.27)
				)
			)
		)
		(property "Value" "1KR2F-3-GP"
			(at 0.064008 -3.993896 0)
			(unlocked yes)
			(layer "F.Fab")
			(hide yes)
			(effects
				(font
					(size 1.016 1.016)
					(thickness 0.1524)
				)
			)
		)
		(property "Device Type" "R402H16"
			(at 0.064008 -5.517896 0)
			(unlocked yes)
			(layer "F.Fab")
			(hide yes)
			(effects
				(font
					(size 1.016 1.016)
					(thickness 0.1524)
				)
			)
		)
		(duplicate_pad_numbers_are_jumpers no)
		(fp_line
			(start -0.508 -0.9398)
			(end -0.508 0.9398)
			(stroke
				(width 0.1524)
				(type default)
			)
			(layer "F.SilkS")
		)
		(fp_line
			(start 0.508 -0.9398)
			(end -0.508 -0.9398)
			(stroke
				(width 0.1524)
				(type default)
			)
			(layer "F.SilkS")
		)
		(fp_rect
			(start -0.508 0.9398)
			(end 0.508 -0.9398)
			(stroke
				(width 0)
				(type default)
			)
			(fill no)
			(layer "F.CrtYd")
		)
		(fp_rect
			(start -0.508 0.9398)
			(end 0.508 -0.9398)
			(stroke
				(width 0)
				(type default)
			)
			(fill no)
			(layer "F.Fab")
		)
		(pad "1" smd custom
			(at 0 -0.4445)
			(size 0.1397 0.1397)
			(layers "F.Cu" "F.Mask" "F.Paste")
			(net "P3V3_STBY")
			(options
				(clearance outline)
				(anchor circle)
			)
			(primitives
				(gr_poly
					(pts
						(arc
							(start -0.1778 -0.2794)
							(mid -0.249642 -0.249642)
							(end -0.2794 -0.1778)
						)
						(arc
							(start -0.2794 0.1778)
							(mid -0.249642 0.249642)
							(end -0.1778 0.2794)
						)
						(arc
							(start 0.1778 0.2794)
							(mid 0.249642 0.249642)
							(end 0.2794 0.1778)
						)
						(arc
							(start 0.2794 -0.1778)
							(mid 0.249642 -0.249642)
							(end 0.1778 -0.2794)
						)
					)
					(width 0)
					(fill yes)
				)
			)
		)
		(pad "2" smd custom
			(at 0 0.4445)
			(size 0.1397 0.1397)
			(layers "F.Cu" "F.Mask" "F.Paste")
			(net "DIVIDER_1_IN")
			(options
				(clearance outline)
				(anchor circle)
			)
			(primitives
				(gr_poly
					(pts
						(arc
							(start -0.1778 -0.2794)
							(mid -0.249642 -0.249642)
							(end -0.2794 -0.1778)
						)
						(arc
							(start -0.2794 0.1778)
							(mid -0.249642 0.249642)
							(end -0.1778 0.2794)
						)
						(arc
							(start 0.1778 0.2794)
							(mid 0.249642 0.249642)
							(end 0.2794 0.1778)
						)
						(arc
							(start 0.2794 -0.1778)
							(mid 0.249642 -0.249642)
							(end 0.1778 -0.2794)
						)
					)
					(width 0)
					(fill yes)
				)
			)
		)
	)
	(footprint ""
		(layer "F.Cu")
		(at 65.913 -38.608 -90)
		(property "Reference" "PU2"
			(at 0 0 270)
			(layer "F.SilkS")
			(hide yes)
			(effects
				(font
					(size 1.27 1.27)
				)
			)
		)
		(property "Value" "TPS53319DQPR-GP"
			(at 4.7498 -5.6896 270)
			(unlocked yes)
			(layer "F.Fab")
			(hide yes)
			(effects
				(font
					(size 1.016 1.016)
					(thickness 0.1524)
				)
			)
		)
		(property "Device Type" "QFN22G6050-G6133H60"
			(at 4.7498 -7.2136 270)
			(unlocked yes)
			(layer "F.Fab")
			(hide yes)
			(effects
				(font
					(size 1.016 1.016)
					(thickness 0.1524)
				)
			)
		)
		(duplicate_pad_numbers_are_jumpers no)
		(fp_line
			(start -3.556 3.5179)
			(end -2.286 3.5179)
			(stroke
				(width 0.1524)
				(type default)
			)
			(layer "F.SilkS")
		)
		(fp_line
			(start 2.286 3.5179)
			(end 3.556 3.5179)
			(stroke
				(width 0.1524)
				(type default)
			)
			(layer "F.SilkS")
		)
		(fp_line
			(start 3.556 3.5179)
			(end 3.556 2.2479)
			(stroke
				(width 0.1524)
				(type default)
			)
			(layer "F.SilkS")
		)
		(fp_line
			(start -0.999998 3.262122)
			(end -0.999998 3.770122)
			(stroke
				(width 0.1524)
				(type default)
			)
			(layer "F.SilkS")
		)
		(fp_line
			(start 1.500124 3.262122)
			(end 1.500124 4.024122)
			(stroke
				(width 0.1524)
				(type default)
			)
			(layer "F.SilkS")
		)
		(fp_line
			(start -3.556 2.2479)
			(end -3.556 3.5179)
			(stroke
				(width 0.1524)
				(type default)
			)
			(layer "F.SilkS")
		)
		(fp_line
			(start -1.999996 -3.262122)
			(end -1.999996 -4.024122)
			(stroke
				(width 0.1524)
				(type default)
			)
			(layer "F.SilkS")
		)
		(fp_line
			(start 0.500126 -3.262122)
			(end 0.500126 -3.770122)
			(stroke
				(width 0.1524)
				(type default)
			)
			(layer "F.SilkS")
		)
		(fp_line
			(start -3.556 -3.5179)
			(end -3.556 -2.2479)
			(stroke
				(width 0.1524)
				(type default)
			)
			(layer "F.SilkS")
		)
		(fp_line
			(start -2.286 -3.5179)
			(end -3.556 -3.5179)
			(stroke
				(width 0.1524)
				(type default)
			)
			(layer "F.SilkS")
		)
		(fp_poly
			(pts
				(xy 3.556 -3.5179) (xy 2.5273 -3.5179) (xy 3.556 -2.4892)
			)
			(stroke
				(width 0)
				(type default)
			)
			(fill yes)
			(layer "F.SilkS")
		)
		(fp_rect
			(start -2.9972 2.5019)
			(end 2.9972 -2.5019)
			(stroke
				(width 0)
				(type default)
			)
			(fill no)
			(layer "F.CrtYd")
		)
		(fp_poly
			(pts
				(xy 3.556 -2.5019) (xy -2.9972 -2.5019) (xy -2.9972 2.5019) (xy 2.9972 2.5019) (xy 2.9972 -2.4892)
				(xy 3.556 -2.4892) (xy 3.556 3.5179) (xy -3.556 3.5179) (xy -3.556 -3.5179) (xy 3.556 -3.5179)
			)
			(stroke
				(width 0)
				(type default)
			)
			(fill no)
			(layer "F.CrtYd")
		)
		(fp_rect
			(start -3.556 3.5179)
			(end 3.556 -3.5179)
			(stroke
				(width 0)
				(type default)
			)
			(fill no)
			(layer "F.Fab")
		)
		(pad "1" smd rect
			(at 2.500122 -2.449322 270)
			(size 0.3048 1.1176)
			(layers "F.Cu" "F.Mask" "F.Paste")
			(net "P3V3_STBY_VFB")
		)
		(pad "2" smd rect
			(at 1.999996 -2.449322 270)
			(size 0.3048 1.1176)
			(layers "F.Cu" "F.Mask" "F.Paste")
			(net "P3V3_STBY_EN")
		)
		(pad "3" smd rect
			(at 1.500124 -2.449322 270)
			(size 0.3048 1.1176)
			(layers "F.Cu" "F.Mask" "F.Paste")
			(net "P3V3_STBY_PG")
		)
		(pad "4" smd rect
			(at 0.999998 -2.449322 270)
			(size 0.3048 1.1176)
			(layers "F.Cu" "F.Mask" "F.Paste")
			(net "P3V3_STBY_VBST")
		)
		(pad "5" smd rect
			(at 0.500126 -2.449322 270)
			(size 0.3048 1.1176)
			(layers "F.Cu" "F.Mask" "F.Paste")
			(net "P3V3_STBY_ROVP")
		)
		(pad "6" smd rect
			(at 0 -2.449322 270)
			(size 0.3048 1.1176)
			(layers "F.Cu" "F.Mask" "F.Paste")
			(net "P3V3_STBY_LL")
		)
		(pad "7" smd rect
			(at -0.500126 -2.449322 270)
			(size 0.3048 1.1176)
			(layers "F.Cu" "F.Mask" "F.Paste")
			(net "P3V3_STBY_LL")
		)
		(pad "8" smd rect
			(at -0.999998 -2.449322 270)
			(size 0.3048 1.1176)
			(layers "F.Cu" "F.Mask" "F.Paste")
			(net "P3V3_STBY_LL")
		)
		(pad "9" smd rect
			(at -1.500124 -2.449322 270)
			(size 0.3048 1.1176)
			(layers "F.Cu" "F.Mask" "F.Paste")
			(net "P3V3_STBY_LL")
		)
		(pad "10" smd rect
			(at -1.999996 -2.449322 270)
			(size 0.3048 1.1176)
			(layers "F.Cu" "F.Mask" "F.Paste")
			(net "P3V3_STBY_LL")
		)
		(pad "11" smd rect
			(at -2.500122 -2.449322 270)
			(size 0.3048 1.1176)
			(layers "F.Cu" "F.Mask" "F.Paste")
			(net "P3V3_STBY_LL")
		)
		(pad "12" smd rect
			(at -2.500122 2.449322 270)
			(size 0.3048 1.1176)
			(layers "F.Cu" "F.Mask" "F.Paste")
			(net "P3V3_STBY_VIN")
		)
		(pad "13" smd rect
			(at -1.999996 2.449322 270)
			(size 0.3048 1.1176)
			(layers "F.Cu" "F.Mask" "F.Paste")
			(net "P3V3_STBY_VIN")
		)
		(pad "14" smd rect
			(at -1.500124 2.449322 270)
			(size 0.3048 1.1176)
			(layers "F.Cu" "F.Mask" "F.Paste")
			(net "P3V3_STBY_VIN")
		)
		(pad "15" smd rect
			(at -0.999998 2.449322 270)
			(size 0.3048 1.1176)
			(layers "F.Cu" "F.Mask" "F.Paste")
			(net "P3V3_STBY_VIN")
		)
		(pad "16" smd rect
			(at -0.500126 2.449322 270)
			(size 0.3048 1.1176)
			(layers "F.Cu" "F.Mask" "F.Paste")
			(net "P3V3_STBY_VIN")
		)
		(pad "17" smd rect
			(at 0 2.449322 270)
			(size 0.3048 1.1176)
			(layers "F.Cu" "F.Mask" "F.Paste")
			(net "P3V3_STBY_VIN")
		)
		(pad "18" smd rect
			(at 0.500126 2.449322 270)
			(size 0.3048 1.1176)
			(layers "F.Cu" "F.Mask" "F.Paste")
			(net "P3V3_STBY_VREG")
		)
		(pad "19" smd rect
			(at 0.999998 2.449322 270)
			(size 0.3048 1.1176)
			(layers "F.Cu" "F.Mask" "F.Paste")
			(net "P3V3_STBY_VDD")
		)
		(pad "20" smd rect
			(at 1.500124 2.449322 270)
			(size 0.3048 1.1176)
			(layers "F.Cu" "F.Mask" "F.Paste")
			(net "P3V3_STBY_MODE")
		)
		(pad "21" smd rect
			(at 1.999996 2.449322 270)
			(size 0.3048 1.1176)
			(layers "F.Cu" "F.Mask" "F.Paste")
			(net "P3V3_STBY_TRIP")
		)
		(pad "22" smd rect
			(at 2.500122 2.449322 270)
			(size 0.3048 1.1176)
			(layers "F.Cu" "F.Mask" "F.Paste")
			(net "P3V3_STBY_RF")
		)
		(pad "23" smd custom
			(at 0 0 270)
			(size 0.83185 0.83185)
			(layers "F.Cu" "F.Mask" "F.Paste")
			(net "GND")
			(options
				(clearance outline)
				(anchor circle)
			)
			(primitives
				(gr_poly
					(pts
						(xy -2.7813 1.6637) (xy -2.7813 1.2954) (xy -3.048 1.2954) (xy -3.048 0.9525) (xy -2.7813 0.9525)
						(xy -2.7813 -0.9525) (xy -3.048 -0.9525) (xy -3.048 -1.2954) (xy -2.7813 -1.2954) (xy -2.7813 -1.6637)
						(xy 2.7813 -1.6637) (xy 2.7813 -1.2954) (xy 3.048 -1.2954) (xy 3.048 -0.9525) (xy 2.7813 -0.9525)
						(xy 2.7813 0.9525) (xy 3.048 0.9525) (xy 3.048 1.2954) (xy 2.7813 1.2954) (xy 2.7813 1.6637)
					)
					(width 0)
					(fill yes)
				)
			)
		)
	)
	(footprint ""
		(layer "F.Cu")
		(at 25.6286 -45.6184)
		(property "Reference" "C334"
			(at 0 0 0)
			(layer "F.SilkS")
			(hide yes)
			(effects
				(font
					(size 1.27 1.27)
				)
			)
		)
		(property "Value" "SCD1U16V2KX-3GP"
			(at 1.1811 -2.7051 0)
			(unlocked yes)
			(layer "F.Fab")
			(hide yes)
			(effects
				(font
					(size 1.016 1.016)
					(thickness 0.1524)
				)
			)
		)
		(property "Device Type" "C402H22"
			(at 1.1811 -4.2291 0)
			(unlocked yes)
			(layer "F.Fab")
			(hide yes)
			(effects
				(font
					(size 1.016 1.016)
					(thickness 0.1524)
				)
			)
		)
		(duplicate_pad_numbers_are_jumpers no)
		(fp_rect
			(start -0.4318 0.9525)
			(end 0.4318 -0.9525)
			(stroke
				(width 0)
				(type default)
			)
			(fill no)
			(layer "F.CrtYd")
		)
		(fp_rect
			(start -0.4318 0.9525)
			(end 0.4318 -0.9525)
			(stroke
				(width 0)
				(type default)
			)
			(fill no)
			(layer "F.Fab")
		)
		(pad "1" smd custom
			(at 0 -0.4445)
			(size 0.1524 0.1524)
			(layers "F.Cu" "F.Mask" "F.Paste")
			(net "NIC0_CT_POWER")
			(options
				(clearance outline)
				(anchor circle)
			)
			(primitives
				(gr_poly
					(pts
						(arc
							(start 0.3048 -0.2032)
							(mid 0.275042 -0.275042)
							(end 0.2032 -0.3048)
						)
						(arc
							(start -0.2032 -0.3048)
							(mid -0.275042 -0.275042)
							(end -0.3048 -0.2032)
						)
						(arc
							(start -0.3048 0.2032)
							(mid -0.275042 0.275042)
							(end -0.2032 0.3048)
						)
						(arc
							(start 0.2032 0.3048)
							(mid 0.275042 0.275042)
							(end 0.3048 0.2032)
						)
					)
					(width 0)
					(fill yes)
				)
			)
		)
		(pad "2" smd custom
			(at 0 0.4445)
			(size 0.1524 0.1524)
			(layers "F.Cu" "F.Mask" "F.Paste")
			(net "GND")
			(options
				(clearance outline)
				(anchor circle)
			)
			(primitives
				(gr_poly
					(pts
						(arc
							(start 0.3048 -0.2032)
							(mid 0.275042 -0.275042)
							(end 0.2032 -0.3048)
						)
						(arc
							(start -0.2032 -0.3048)
							(mid -0.275042 -0.275042)
							(end -0.3048 -0.2032)
						)
						(arc
							(start -0.3048 0.2032)
							(mid -0.275042 0.275042)
							(end -0.2032 0.3048)
						)
						(arc
							(start 0.2032 0.3048)
							(mid 0.275042 0.275042)
							(end 0.3048 0.2032)
						)
					)
					(width 0)
					(fill yes)
				)
			)
		)
	)
	(footprint ""
		(layer "F.Cu")
		(at 38.968934 -77.560932 180)
		(property "Reference" "PC66"
			(at 0 0 180)
			(layer "F.SilkS")
			(hide yes)
			(effects
				(font
					(size 1.27 1.27)
				)
			)
		)
		(property "Value" "SC22U16V5MX-4-GP"
			(at -0.0762 -6.1214 180)
			(unlocked yes)
			(layer "F.Fab")
			(hide yes)
			(effects
				(font
					(size 1.016 1.016)
					(thickness 0.1524)
				)
			)
		)
		(property "Device Type" "C805H58"
			(at -0.0762 -8.1534 180)
			(unlocked yes)
			(layer "F.Fab")
			(hide yes)
			(effects
				(font
					(size 1.016 1.016)
					(thickness 0.1524)
				)
			)
		)
		(duplicate_pad_numbers_are_jumpers no)
		(fp_line
			(start 0.635 0)
			(end -0.635 0)
			(stroke
				(width 0.508)
				(type default)
			)
			(layer "F.SilkS")
		)
		(fp_rect
			(start -0.9652 1.778)
			(end 0.9652 -1.778)
			(stroke
				(width 0)
				(type default)
			)
			(fill no)
			(layer "F.CrtYd")
		)
		(fp_poly
			(pts
				(xy -0.9652 -1.778) (xy 0.9652 -1.778) (xy 0.9652 1.778) (xy -0.9652 1.778)
			)
			(stroke
				(width 0)
				(type default)
			)
			(fill no)
			(layer "F.Fab")
		)
		(pad "1" smd rect
			(at 0 -0.9652 180)
			(size 1.397 1.143)
			(layers "F.Cu" "F.Mask" "F.Paste")
			(net "P5V_STBY_LR")
		)
		(pad "2" smd rect
			(at 0 0.9652 180)
			(size 1.397 1.143)
			(layers "F.Cu" "F.Mask" "F.Paste")
			(net "GND")
		)
	)
	(footprint ""
		(layer "F.Cu")
		(at 49.657 -152.4 180)
		(property "Reference" "R160"
			(at 0 0 180)
			(layer "F.SilkS")
			(hide yes)
			(effects
				(font
					(size 1.27 1.27)
				)
			)
		)
		(property "Value" "4K7R2F-GP"
			(at 0.064008 -3.993896 180)
			(unlocked yes)
			(layer "F.Fab")
			(hide yes)
			(effects
				(font
					(size 1.016 1.016)
					(thickness 0.1524)
				)
			)
		)
		(property "Device Type" "R402H16"
			(at 0.064008 -5.517896 180)
			(unlocked yes)
			(layer "F.Fab")
			(hide yes)
			(effects
				(font
					(size 1.016 1.016)
					(thickness 0.1524)
				)
			)
		)
		(duplicate_pad_numbers_are_jumpers no)
		(fp_line
			(start 0.508 -0.9398)
			(end -0.508 -0.9398)
			(stroke
				(width 0.1524)
				(type default)
			)
			(layer "F.SilkS")
		)
		(fp_line
			(start -0.508 -0.9398)
			(end -0.508 0.9398)
			(stroke
				(width 0.1524)
				(type default)
			)
			(layer "F.SilkS")
		)
		(fp_rect
			(start -0.508 0.9398)
			(end 0.508 -0.9398)
			(stroke
				(width 0)
				(type default)
			)
			(fill no)
			(layer "F.CrtYd")
		)
		(fp_rect
			(start -0.508 0.9398)
			(end 0.508 -0.9398)
			(stroke
				(width 0)
				(type default)
			)
			(fill no)
			(layer "F.Fab")
		)
		(pad "1" smd custom
			(at 0 -0.4445 180)
			(size 0.1397 0.1397)
			(layers "F.Cu" "F.Mask" "F.Paste")
			(net "TEMP_2_A2")
			(options
				(clearance outline)
				(anchor circle)
			)
			(primitives
				(gr_poly
					(pts
						(arc
							(start -0.1778 -0.2794)
							(mid -0.249642 -0.249642)
							(end -0.2794 -0.1778)
						)
						(arc
							(start -0.2794 0.1778)
							(mid -0.249642 0.249642)
							(end -0.1778 0.2794)
						)
						(arc
							(start 0.1778 0.2794)
							(mid 0.249642 0.249642)
							(end 0.2794 0.1778)
						)
						(arc
							(start 0.2794 -0.1778)
							(mid 0.249642 -0.249642)
							(end 0.1778 -0.2794)
						)
					)
					(width 0)
					(fill yes)
				)
			)
		)
		(pad "2" smd custom
			(at 0 0.4445 180)
			(size 0.1397 0.1397)
			(layers "F.Cu" "F.Mask" "F.Paste")
			(net "GND")
			(options
				(clearance outline)
				(anchor circle)
			)
			(primitives
				(gr_poly
					(pts
						(arc
							(start -0.1778 -0.2794)
							(mid -0.249642 -0.249642)
							(end -0.2794 -0.1778)
						)
						(arc
							(start -0.2794 0.1778)
							(mid -0.249642 0.249642)
							(end -0.1778 0.2794)
						)
						(arc
							(start 0.1778 0.2794)
							(mid 0.249642 0.249642)
							(end 0.2794 0.1778)
						)
						(arc
							(start 0.2794 -0.1778)
							(mid 0.249642 -0.249642)
							(end 0.1778 -0.2794)
						)
					)
					(width 0)
					(fill yes)
				)
			)
		)
	)
)
